# S9S_MB_2U (Grand Teton) — schematic netlist excerpt (pin names and nets, part order shuffled) for the footprints in the layout excerpt that follows; sources: Cadence DE-HDL packaged netlist, KiCad conversion of 03242023_DA0F0TMBIJ0_F0T_Motherboard_J_brd_V01_OCP.brd

PR1134  Q_RES  120K 1% CHIP  pkg 0402LF  page 302 : A = AGND_HSC ; B = HSC_MODE_1
C1100  Q_CAP_DIFFBUS  DIFF BUS_0.22UF 6.3V 20% X6S  pkg C0201  page 181 : \1\ = P3E_PCH_M2_TX_DP<2> ; \2\ = P3E_PCH_M2_TX_C_DP<2>

(kicad_pcb
	(version 20260206)
	(generator "pcbnew")
	(generator_version "10.0")
	(general
		(thickness 1.6)
		(legacy_teardrops no)
	)
	(paper "A4")
	(title_block
		(title "03242023_DA0F0TMBIJ0_F0T_Motherboard_J_brd_V01_OCP.brd")
		(comment 1 "Grand Teton / footprints 3890-3891 of 6105")
	)
	(layers
		(0 "F.Cu" signal "TOP")
		(4 "In1.Cu" signal "GND")
		(6 "In2.Cu" signal "IN1")
		(8 "In3.Cu" signal "GND1")
		(10 "In4.Cu" signal "IN2")
		(12 "In5.Cu" signal "GND2")
		(14 "In6.Cu" signal "IN3")
		(16 "In7.Cu" signal "GND3")
		(18 "In8.Cu" signal "VCC")
		(20 "In9.Cu" signal "VCC1")
		(22 "In10.Cu" signal "GND4")
		(24 "In11.Cu" signal "IN4")
		(26 "In12.Cu" signal "GND5")
		(28 "In13.Cu" signal "IN5")
		(30 "In14.Cu" signal "GND6")
		(32 "In15.Cu" signal "IN6")
		(34 "In16.Cu" signal "GND7")
		(2 "B.Cu" signal "BOTTOM")
		(9 "F.Adhes" user "F.Adhesive")
		(11 "B.Adhes" user "B.Adhesive")
		(13 "F.Paste" user "Package Geometry/Pastemask Top")
		(15 "B.Paste" user "Package Geometry/Pastemask Bottom")
		(5 "F.SilkS" user "Ref Des/Silkscreen Top")
		(7 "B.SilkS" user "Ref Des/Silkscreen Bottom")
		(1 "F.Mask" user "Board Geometry/Soldermask Top")
		(3 "B.Mask" user "Board Geometry/Soldermask Bottom")
		(17 "Dwgs.User" user "User.Drawings")
		(19 "Cmts.User" user "User.Comments")
		(21 "Eco1.User" user "User.Eco1")
		(23 "Eco2.User" user "User.Eco2")
		(25 "Edge.Cuts" user "Board Geometry/Outline")
		(27 "Margin" user)
		(31 "F.CrtYd" user "Package Geometry/Place Bound Top")
		(29 "B.CrtYd" user "Package Geometry/Place Bound Bottom")
		(35 "F.Fab" user "Ref Des/Assembly Top")
		(33 "B.Fab" user "Ref Des/Assembly Bottom")
	)
	(footprint ""
		(layer "F.Cu")
		(at 205.397608 -407.871422 180)
		(property "Reference" "PR1134"
			(at 0 0 180)
			(layer "F.SilkS")
			(hide yes)
			(effects
				(font
					(size 1.27 1.27)
				)
			)
		)
		(property "Value" ""
			(at 0 0 180)
			(layer "F.Fab")
			(effects
				(font
					(size 1.27 1.27)
				)
			)
		)
		(duplicate_pad_numbers_are_jumpers no)
		(fp_line
			(start 0.7874 0.4064)
			(end -0.7874 0.4064)
			(stroke
				(width 0.1524)
				(type default)
			)
			(layer "F.SilkS")
		)
		(fp_line
			(start 0.7874 -0.4064)
			(end 0.7874 0.4064)
			(stroke
				(width 0.1524)
				(type default)
			)
			(layer "F.SilkS")
		)
		(fp_line
			(start -0.7874 0.4064)
			(end -0.7874 -0.4064)
			(stroke
				(width 0.1524)
				(type default)
			)
			(layer "F.SilkS")
		)
		(fp_line
			(start -0.7874 -0.4064)
			(end 0.7874 -0.4064)
			(stroke
				(width 0.1524)
				(type default)
			)
			(layer "F.SilkS")
		)
		(fp_line
			(start 0.67945 0.3048)
			(end 0.120396 0.3048)
			(stroke
				(width 0.1)
				(type default)
			)
			(layer "F.Fab")
		)
		(fp_line
			(start 0.67945 -0.3048)
			(end 0.67945 0.3048)
			(stroke
				(width 0.1)
				(type default)
			)
			(layer "F.Fab")
		)
		(fp_line
			(start 0.12065 -0.2794)
			(end 0.12065 -0.3048)
			(stroke
				(width 0.1)
				(type default)
			)
			(layer "F.Fab")
		)
		(fp_line
			(start 0.12065 -0.3048)
			(end 0.67945 -0.3048)
			(stroke
				(width 0.1)
				(type default)
			)
			(layer "F.Fab")
		)
		(fp_line
			(start 0.120396 0.3048)
			(end 0.120396 0.2794)
			(stroke
				(width 0.1)
				(type default)
			)
			(layer "F.Fab")
		)
		(fp_line
			(start 0.120396 0.2794)
			(end -0.12065 0.2794)
			(stroke
				(width 0.1)
				(type default)
			)
			(layer "F.Fab")
		)
		(fp_line
			(start -0.12065 0.3048)
			(end -0.67945 0.3048)
			(stroke
				(width 0.1)
				(type default)
			)
			(layer "F.Fab")
		)
		(fp_line
			(start -0.12065 0.2794)
			(end -0.12065 0.3048)
			(stroke
				(width 0.1)
				(type default)
			)
			(layer "F.Fab")
		)
		(fp_line
			(start -0.12065 -0.2794)
			(end 0.12065 -0.2794)
			(stroke
				(width 0.1)
				(type default)
			)
			(layer "F.Fab")
		)
		(fp_line
			(start -0.12065 -0.305054)
			(end -0.12065 -0.2794)
			(stroke
				(width 0.1)
				(type default)
			)
			(layer "F.Fab")
		)
		(fp_line
			(start -0.67945 0.3048)
			(end -0.67945 -0.305054)
			(stroke
				(width 0.1)
				(type default)
			)
			(layer "F.Fab")
		)
		(fp_line
			(start -0.67945 -0.305054)
			(end -0.12065 -0.305054)
			(stroke
				(width 0.1)
				(type default)
			)
			(layer "F.Fab")
		)
		(pad "1" smd circle
			(at -0.40005 0 180)
			(size 0 0)
			(layers "F.Cu" "F.Mask" "F.Paste")
			(net "AGND_HSC")
		)
		(pad "2" smd circle
			(at 0.40005 0 180)
			(size 0 0)
			(layers "F.Cu" "F.Mask" "F.Paste")
			(net "HSC_MODE_1")
		)
	)
	(footprint ""
		(layer "F.Cu")
		(at 180.528468 -48.053498 180)
		(property "Reference" "C1100"
			(at 0 0 180)
			(layer "F.SilkS")
			(hide yes)
			(effects
				(font
					(size 1.27 1.27)
				)
			)
		)
		(property "Value" ""
			(at 0 0 180)
			(layer "F.Fab")
			(effects
				(font
					(size 1.27 1.27)
				)
			)
		)
		(duplicate_pad_numbers_are_jumpers no)
		(fp_line
			(start 0.299974 0.150114)
			(end -0.299974 0.150114)
			(stroke
				(width 0.1)
				(type default)
			)
			(layer "F.Fab")
		)
		(fp_line
			(start 0.299974 -0.150114)
			(end 0.299974 0.150114)
			(stroke
				(width 0.1)
				(type default)
			)
			(layer "F.Fab")
		)
		(fp_line
			(start -0.299974 0.150114)
			(end -0.299974 -0.150114)
			(stroke
				(width 0.1)
				(type default)
			)
			(layer "F.Fab")
		)
		(fp_line
			(start -0.299974 -0.150114)
			(end 0.299974 -0.150114)
			(stroke
				(width 0.1)
				(type default)
			)
			(layer "F.Fab")
		)
		(pad "1" smd rect
			(at -0.2667 0 180)
			(size 0.3048 0.381)
			(layers "F.Cu" "F.Mask" "F.Paste")
			(net "P3E_PCH_M2_TX_DP<2>")
		)
		(pad "2" smd rect
			(at 0.2667 0 180)
			(size 0.3048 0.381)
			(layers "F.Cu" "F.Mask" "F.Paste")
			(net "P3E_PCH_M2_TX_C_DP<2>")
		)
		(zone
			(layer "In1.Cu")
			(hatch none 0.5)
			(connect_pads
				(clearance 0)
			)
			(min_thickness 0.25)
			(keepout
				(tracks not_allowed)
				(vias allowed)
				(pads allowed)
				(copperpour not_allowed)
				(footprints allowed)
			)
			(placement
				(enabled no)
				(sheetname "")
			)
			(fill
				(thermal_gap 0.5)
				(thermal_bridge_width 0.5)
				(island_removal_mode 0)
			)
			(polygon
				(pts
					(arc
						(start 180.388768 -48.294798)
						(mid 180.44265 -48.27248)
						(end 180.464968 -48.218598)
					)
					(arc
						(start 180.464968 -47.888398)
						(mid 180.44265 -47.834516)
						(end 180.388768 -47.812198)
					)
					(arc
						(start 180.134768 -47.812198)
						(mid 180.080886 -47.834516)
						(end 180.058568 -47.888398)
					)
					(arc
						(start 180.058568 -48.218598)
						(mid 180.080886 -48.27248)
						(end 180.134768 -48.294798)
					)
				)
			)
		)
		(zone
			(layer "In1.Cu")
			(hatch none 0.5)
			(connect_pads
				(clearance 0)
			)
			(min_thickness 0.25)
			(keepout
				(tracks not_allowed)
				(vias allowed)
				(pads allowed)
				(copperpour not_allowed)
				(footprints allowed)
			)
			(placement
				(enabled no)
				(sheetname "")
			)
			(fill
				(thermal_gap 0.5)
				(thermal_bridge_width 0.5)
				(island_removal_mode 0)
			)
			(polygon
				(pts
					(arc
						(start 180.922168 -48.294798)
						(mid 180.97605 -48.27248)
						(end 180.998368 -48.218598)
					)
					(arc
						(start 180.998368 -47.888398)
						(mid 180.97605 -47.834516)
						(end 180.922168 -47.812198)
					)
					(arc
						(start 180.668168 -47.812198)
						(mid 180.614286 -47.834516)
						(end 180.591968 -47.888398)
					)
					(arc
						(start 180.591968 -48.218598)
						(mid 180.614286 -48.27248)
						(end 180.668168 -48.294798)
					)
				)
			)
		)
	)
)
